# T6G (Grand Teton) — schematic netlist excerpt (pin names and nets, part order shuffled) for the footprints in the layout excerpt that follows; sources: Cadence DE-HDL packaged netlist, KiCad conversion of 04192023_DAF0TMB3IC0_F0TG_MB_C_brd_V02_OCP.brd

C6709  Q_CAP_DIFFBUS  DIFF BUS_0.22UF 6.3V 20% X6S  pkg C0201  page 341 : \1\ = P5E_CPU1_P2_TX_BUF_C_DP<8> ; \2\ = P5E_CPU1_P2_TX_BUF_DP<8>
R3193  Q_RES  33.2 1% CHIP  pkg 0402LF  page 139 : A = IRQ_LVC3_V3_2_WAKE_BUF_N ; B = IRQ_OCP_V3_2_WAKE_BUF_N
R1647  Q_RES  1K 1% CHIP  pkg 0402LF  page 174 : A = PVDD18_S5_P0 ; B = FM_PLD_CPU0_PRSNT_HDT_N

(kicad_pcb
	(version 20260206)
	(generator "pcbnew")
	(generator_version "10.0")
	(general
		(thickness 1.6)
		(legacy_teardrops no)
	)
	(paper "A4")
	(title_block
		(title "04192023_DAF0TMB3IC0_F0TG_MB_C_brd_V02_OCP.brd")
		(comment 1 "Grand Teton / footprints 2939-2941 of 8354")
	)
	(layers
		(0 "F.Cu" signal "TOP")
		(4 "In1.Cu" signal "GND")
		(6 "In2.Cu" signal "IN1")
		(8 "In3.Cu" signal "GND1")
		(10 "In4.Cu" signal "IN2")
		(12 "In5.Cu" signal "GND2")
		(14 "In6.Cu" signal "IN3")
		(16 "In7.Cu" signal "GND3")
		(18 "In8.Cu" signal "VCC")
		(20 "In9.Cu" signal "VCC1")
		(22 "In10.Cu" signal "GND4")
		(24 "In11.Cu" signal "IN4")
		(26 "In12.Cu" signal "GND5")
		(28 "In13.Cu" signal "IN5")
		(30 "In14.Cu" signal "GND6")
		(32 "In15.Cu" signal "IN6")
		(34 "In16.Cu" signal "GND7")
		(2 "B.Cu" signal "BOTTOM")
		(9 "F.Adhes" user "F.Adhesive")
		(11 "B.Adhes" user "B.Adhesive")
		(13 "F.Paste" user "Package Geometry/Pastemask Top")
		(15 "B.Paste" user "Package Geometry/Pastemask Bottom")
		(5 "F.SilkS" user "Ref Des/Silkscreen Top")
		(7 "B.SilkS" user "Ref Des/Silkscreen Bottom")
		(1 "F.Mask" user "Board Geometry/Soldermask Top")
		(3 "B.Mask" user "Board Geometry/Soldermask Bottom")
		(17 "Dwgs.User" user "User.Drawings")
		(19 "Cmts.User" user "User.Comments")
		(21 "Eco1.User" user "User.Eco1")
		(23 "Eco2.User" user "User.Eco2")
		(25 "Edge.Cuts" user "Board Geometry/Outline")
		(27 "Margin" user)
		(31 "F.CrtYd" user "Package Geometry/Place Bound Top")
		(29 "B.CrtYd" user "Package Geometry/Place Bound Bottom")
		(35 "F.Fab" user "Ref Des/Assembly Top")
		(33 "B.Fab" user "Ref Des/Assembly Bottom")
	)
	(footprint ""
		(layer "F.Cu")
		(at 100.941124 -34.28492)
		(property "Reference" "R3193"
			(at 0 0 0)
			(layer "F.SilkS")
			(hide yes)
			(effects
				(font
					(size 1.27 1.27)
				)
			)
		)
		(property "Value" ""
			(at 0 0 0)
			(layer "F.Fab")
			(effects
				(font
					(size 1.27 1.27)
				)
			)
		)
		(duplicate_pad_numbers_are_jumpers no)
		(fp_line
			(start -0.7874 -0.4064)
			(end 0.7874 -0.4064)
			(stroke
				(width 0.1524)
				(type default)
			)
			(layer "F.SilkS")
		)
		(fp_line
			(start -0.7874 0.4064)
			(end -0.7874 -0.4064)
			(stroke
				(width 0.1524)
				(type default)
			)
			(layer "F.SilkS")
		)
		(fp_line
			(start 0.7874 -0.4064)
			(end 0.7874 0.4064)
			(stroke
				(width 0.1524)
				(type default)
			)
			(layer "F.SilkS")
		)
		(fp_line
			(start 0.7874 0.4064)
			(end -0.7874 0.4064)
			(stroke
				(width 0.1524)
				(type default)
			)
			(layer "F.SilkS")
		)
		(fp_line
			(start -0.67945 -0.305054)
			(end -0.12065 -0.305054)
			(stroke
				(width 0.1)
				(type default)
			)
			(layer "F.Fab")
		)
		(fp_line
			(start -0.67945 0.3048)
			(end -0.67945 -0.305054)
			(stroke
				(width 0.1)
				(type default)
			)
			(layer "F.Fab")
		)
		(fp_line
			(start -0.12065 -0.305054)
			(end -0.12065 -0.2794)
			(stroke
				(width 0.1)
				(type default)
			)
			(layer "F.Fab")
		)
		(fp_line
			(start -0.12065 -0.2794)
			(end 0.12065 -0.2794)
			(stroke
				(width 0.1)
				(type default)
			)
			(layer "F.Fab")
		)
		(fp_line
			(start -0.12065 0.2794)
			(end -0.12065 0.3048)
			(stroke
				(width 0.1)
				(type default)
			)
			(layer "F.Fab")
		)
		(fp_line
			(start -0.12065 0.3048)
			(end -0.67945 0.3048)
			(stroke
				(width 0.1)
				(type default)
			)
			(layer "F.Fab")
		)
		(fp_line
			(start 0.120396 0.2794)
			(end -0.12065 0.2794)
			(stroke
				(width 0.1)
				(type default)
			)
			(layer "F.Fab")
		)
		(fp_line
			(start 0.120396 0.3048)
			(end 0.120396 0.2794)
			(stroke
				(width 0.1)
				(type default)
			)
			(layer "F.Fab")
		)
		(fp_line
			(start 0.12065 -0.3048)
			(end 0.67945 -0.3048)
			(stroke
				(width 0.1)
				(type default)
			)
			(layer "F.Fab")
		)
		(fp_line
			(start 0.12065 -0.2794)
			(end 0.12065 -0.3048)
			(stroke
				(width 0.1)
				(type default)
			)
			(layer "F.Fab")
		)
		(fp_line
			(start 0.67945 -0.3048)
			(end 0.67945 0.3048)
			(stroke
				(width 0.1)
				(type default)
			)
			(layer "F.Fab")
		)
		(fp_line
			(start 0.67945 0.3048)
			(end 0.120396 0.3048)
			(stroke
				(width 0.1)
				(type default)
			)
			(layer "F.Fab")
		)
		(pad "1" smd circle
			(at -0.40005 0)
			(size 0 0)
			(layers "F.Cu" "F.Mask" "F.Paste")
			(net "IRQ_LVC3_V3_2_WAKE_BUF_N")
		)
		(pad "2" smd circle
			(at 0.40005 0)
			(size 0 0)
			(layers "F.Cu" "F.Mask" "F.Paste")
			(net "IRQ_OCP_V3_2_WAKE_BUF_N")
		)
	)
	(footprint ""
		(layer "F.Cu")
		(at 235.718096 -144.958562 180)
		(property "Reference" "R1647"
			(at 0 0 180)
			(layer "F.SilkS")
			(hide yes)
			(effects
				(font
					(size 1.27 1.27)
				)
			)
		)
		(property "Value" ""
			(at 0 0 180)
			(layer "F.Fab")
			(effects
				(font
					(size 1.27 1.27)
				)
			)
		)
		(duplicate_pad_numbers_are_jumpers no)
		(fp_line
			(start 0.7874 0.4064)
			(end -0.7874 0.4064)
			(stroke
				(width 0.1524)
				(type default)
			)
			(layer "F.SilkS")
		)
		(fp_line
			(start 0.7874 -0.4064)
			(end 0.7874 0.4064)
			(stroke
				(width 0.1524)
				(type default)
			)
			(layer "F.SilkS")
		)
		(fp_line
			(start -0.7874 0.4064)
			(end -0.7874 -0.4064)
			(stroke
				(width 0.1524)
				(type default)
			)
			(layer "F.SilkS")
		)
		(fp_line
			(start -0.7874 -0.4064)
			(end 0.7874 -0.4064)
			(stroke
				(width 0.1524)
				(type default)
			)
			(layer "F.SilkS")
		)
		(fp_line
			(start 0.67945 0.3048)
			(end 0.120396 0.3048)
			(stroke
				(width 0.1)
				(type default)
			)
			(layer "F.Fab")
		)
		(fp_line
			(start 0.67945 -0.3048)
			(end 0.67945 0.3048)
			(stroke
				(width 0.1)
				(type default)
			)
			(layer "F.Fab")
		)
		(fp_line
			(start 0.12065 -0.2794)
			(end 0.12065 -0.3048)
			(stroke
				(width 0.1)
				(type default)
			)
			(layer "F.Fab")
		)
		(fp_line
			(start 0.12065 -0.3048)
			(end 0.67945 -0.3048)
			(stroke
				(width 0.1)
				(type default)
			)
			(layer "F.Fab")
		)
		(fp_line
			(start 0.120396 0.3048)
			(end 0.120396 0.2794)
			(stroke
				(width 0.1)
				(type default)
			)
			(layer "F.Fab")
		)
		(fp_line
			(start 0.120396 0.2794)
			(end -0.12065 0.2794)
			(stroke
				(width 0.1)
				(type default)
			)
			(layer "F.Fab")
		)
		(fp_line
			(start -0.12065 0.3048)
			(end -0.67945 0.3048)
			(stroke
				(width 0.1)
				(type default)
			)
			(layer "F.Fab")
		)
		(fp_line
			(start -0.12065 0.2794)
			(end -0.12065 0.3048)
			(stroke
				(width 0.1)
				(type default)
			)
			(layer "F.Fab")
		)
		(fp_line
			(start -0.12065 -0.2794)
			(end 0.12065 -0.2794)
			(stroke
				(width 0.1)
				(type default)
			)
			(layer "F.Fab")
		)
		(fp_line
			(start -0.12065 -0.305054)
			(end -0.12065 -0.2794)
			(stroke
				(width 0.1)
				(type default)
			)
			(layer "F.Fab")
		)
		(fp_line
			(start -0.67945 0.3048)
			(end -0.67945 -0.305054)
			(stroke
				(width 0.1)
				(type default)
			)
			(layer "F.Fab")
		)
		(fp_line
			(start -0.67945 -0.305054)
			(end -0.12065 -0.305054)
			(stroke
				(width 0.1)
				(type default)
			)
			(layer "F.Fab")
		)
		(pad "1" smd circle
			(at -0.40005 0 180)
			(size 0 0)
			(layers "F.Cu" "F.Mask" "F.Paste")
			(net "PVDD18_S5_P0")
		)
		(pad "2" smd circle
			(at 0.40005 0 180)
			(size 0 0)
			(layers "F.Cu" "F.Mask" "F.Paste")
			(net "FM_PLD_CPU0_PRSNT_HDT_N")
		)
	)
	(footprint ""
		(layer "F.Cu")
		(at 140.289026 -408.517344 -90)
		(property "Reference" "C6709"
			(at 0 0 270)
			(layer "F.SilkS")
			(hide yes)
			(effects
				(font
					(size 1.27 1.27)
				)
			)
		)
		(property "Value" ""
			(at 0 0 270)
			(layer "F.Fab")
			(effects
				(font
					(size 1.27 1.27)
				)
			)
		)
		(duplicate_pad_numbers_are_jumpers no)
		(fp_line
			(start -0.299974 0.150114)
			(end -0.299974 -0.150114)
			(stroke
				(width 0.1)
				(type default)
			)
			(layer "F.Fab")
		)
		(fp_line
			(start 0.299974 0.150114)
			(end -0.299974 0.150114)
			(stroke
				(width 0.1)
				(type default)
			)
			(layer "F.Fab")
		)
		(fp_line
			(start -0.299974 -0.150114)
			(end 0.299974 -0.150114)
			(stroke
				(width 0.1)
				(type default)
			)
			(layer "F.Fab")
		)
		(fp_line
			(start 0.299974 -0.150114)
			(end 0.299974 0.150114)
			(stroke
				(width 0.1)
				(type default)
			)
			(layer "F.Fab")
		)
		(pad "1" smd rect
			(at -0.2667 0 270)
			(size 0.3048 0.381)
			(layers "F.Cu" "F.Mask" "F.Paste")
			(net "P5E_CPU1_P2_TX_BUF_C_DP<8>")
		)
		(pad "2" smd rect
			(at 0.2667 0 270)
			(size 0.3048 0.381)
			(layers "F.Cu" "F.Mask" "F.Paste")
			(net "P5E_CPU1_P2_TX_BUF_DP<8>")
		)
	)
)
